(kicad_pcb
	(version 20260206)
	(generator "pcbnew")
	(generator_version "10.0")
	(general
		(thickness 1.6)
		(legacy_teardrops no)
	)
	(paper "A4")
	(title_block
		(title "04192023_DAF0TMB3IC0_F0TG_MB_C_brd_V02_OCP.brd")
		(comment 1 "Grand Teton / footprints 3749-3755 of 8354")
	)
	(layers
		(0 "F.Cu" signal "TOP")
		(4 "In1.Cu" signal "GND")
		(6 "In2.Cu" signal "IN1")
		(8 "In3.Cu" signal "GND1")
		(10 "In4.Cu" signal "IN2")
		(12 "In5.Cu" signal "GND2")
		(14 "In6.Cu" signal "IN3")
		(16 "In7.Cu" signal "GND3")
		(18 "In8.Cu" signal "VCC")
		(20 "In9.Cu" signal "VCC1")
		(22 "In10.Cu" signal "GND4")
		(24 "In11.Cu" signal "IN4")
		(26 "In12.Cu" signal "GND5")
		(28 "In13.Cu" signal "IN5")
		(30 "In14.Cu" signal "GND6")
		(32 "In15.Cu" signal "IN6")
		(34 "In16.Cu" signal "GND7")
		(2 "B.Cu" signal "BOTTOM")
		(9 "F.Adhes" user "F.Adhesive")
		(11 "B.Adhes" user "B.Adhesive")
		(13 "F.Paste" user "Package Geometry/Pastemask Top")
		(15 "B.Paste" user "Package Geometry/Pastemask Bottom")
		(5 "F.SilkS" user "Ref Des/Silkscreen Top")
		(7 "B.SilkS" user "Ref Des/Silkscreen Bottom")
		(1 "F.Mask" user "Board Geometry/Soldermask Top")
		(3 "B.Mask" user "Board Geometry/Soldermask Bottom")
		(17 "Dwgs.User" user "User.Drawings")
		(19 "Cmts.User" user "User.Comments")
		(21 "Eco1.User" user "User.Eco1")
		(23 "Eco2.User" user "User.Eco2")
		(25 "Edge.Cuts" user "Board Geometry/Outline")
		(27 "Margin" user)
		(31 "F.CrtYd" user "Package Geometry/Place Bound Top")
		(29 "B.CrtYd" user "Package Geometry/Place Bound Bottom")
		(35 "F.Fab" user "Ref Des/Assembly Top")
		(33 "B.Fab" user "Ref Des/Assembly Bottom")
	)
	(footprint ""
		(layer "F.Cu")
		(at 105.191814 -36.6522)
		(property "Reference" "R6323"
			(at 0 0 0)
			(layer "F.SilkS")
			(hide yes)
			(effects
				(font
					(size 1.27 1.27)
				)
			)
		)
		(property "Value" ""
			(at 0 0 0)
			(layer "F.Fab")
			(effects
				(font
					(size 1.27 1.27)
				)
			)
		)
		(duplicate_pad_numbers_are_jumpers no)
		(fp_line
			(start -0.7874 -0.4064)
			(end 0.7874 -0.4064)
			(stroke
				(width 0.1524)
				(type default)
			)
			(layer "F.SilkS")
		)
		(fp_line
			(start -0.7874 0.4064)
			(end -0.7874 -0.4064)
			(stroke
				(width 0.1524)
				(type default)
			)
			(layer "F.SilkS")
		)
		(fp_line
			(start 0.7874 -0.4064)
			(end 0.7874 0.4064)
			(stroke
				(width 0.1524)
				(type default)
			)
			(layer "F.SilkS")
		)
		(fp_line
			(start 0.7874 0.4064)
			(end -0.7874 0.4064)
			(stroke
				(width 0.1524)
				(type default)
			)
			(layer "F.SilkS")
		)
		(fp_line
			(start -0.67945 -0.305054)
			(end -0.12065 -0.305054)
			(stroke
				(width 0.1)
				(type default)
			)
			(layer "F.Fab")
		)
		(fp_line
			(start -0.67945 0.3048)
			(end -0.67945 -0.305054)
			(stroke
				(width 0.1)
				(type default)
			)
			(layer "F.Fab")
		)
		(fp_line
			(start -0.12065 -0.305054)
			(end -0.12065 -0.2794)
			(stroke
				(width 0.1)
				(type default)
			)
			(layer "F.Fab")
		)
		(fp_line
			(start -0.12065 -0.2794)
			(end 0.12065 -0.2794)
			(stroke
				(width 0.1)
				(type default)
			)
			(layer "F.Fab")
		)
		(fp_line
			(start -0.12065 0.2794)
			(end -0.12065 0.3048)
			(stroke
				(width 0.1)
				(type default)
			)
			(layer "F.Fab")
		)
		(fp_line
			(start -0.12065 0.3048)
			(end -0.67945 0.3048)
			(stroke
				(width 0.1)
				(type default)
			)
			(layer "F.Fab")
		)
		(fp_line
			(start 0.120396 0.2794)
			(end -0.12065 0.2794)
			(stroke
				(width 0.1)
				(type default)
			)
			(layer "F.Fab")
		)
		(fp_line
			(start 0.120396 0.3048)
			(end 0.120396 0.2794)
			(stroke
				(width 0.1)
				(type default)
			)
			(layer "F.Fab")
		)
		(fp_line
			(start 0.12065 -0.3048)
			(end 0.67945 -0.3048)
			(stroke
				(width 0.1)
				(type default)
			)
			(layer "F.Fab")
		)
		(fp_line
			(start 0.12065 -0.2794)
			(end 0.12065 -0.3048)
			(stroke
				(width 0.1)
				(type default)
			)
			(layer "F.Fab")
		)
		(fp_line
			(start 0.67945 -0.3048)
			(end 0.67945 0.3048)
			(stroke
				(width 0.1)
				(type default)
			)
			(layer "F.Fab")
		)
		(fp_line
			(start 0.67945 0.3048)
			(end 0.120396 0.3048)
			(stroke
				(width 0.1)
				(type default)
			)
			(layer "F.Fab")
		)
		(pad "1" smd circle
			(at -0.40005 0)
			(size 0 0)
			(layers "F.Cu" "F.Mask" "F.Paste")
			(net "USB_HUB2_TI_TEST")
		)
		(pad "2" smd circle
			(at 0.40005 0)
			(size 0 0)
			(layers "F.Cu" "F.Mask" "F.Paste")
			(net "USB_HUB2_TI_TEST_MRP_PROG_FUNC6")
		)
	)
	(footprint ""
		(layer "F.Cu")
		(at 14.265402 -105.537762 90)
		(property "Reference" "R4419"
			(at 0 0 90)
			(layer "F.SilkS")
			(hide yes)
			(effects
				(font
					(size 1.27 1.27)
				)
			)
		)
		(property "Value" ""
			(at 0 0 90)
			(layer "F.Fab")
			(effects
				(font
					(size 1.27 1.27)
				)
			)
		)
		(duplicate_pad_numbers_are_jumpers no)
		(fp_line
			(start 0.7874 -0.4064)
			(end 0.7874 0.4064)
			(stroke
				(width 0.1524)
				(type default)
			)
			(layer "F.SilkS")
		)
		(fp_line
			(start -0.7874 -0.4064)
			(end 0.7874 -0.4064)
			(stroke
				(width 0.1524)
				(type default)
			)
			(layer "F.SilkS")
		)
		(fp_line
			(start 0.7874 0.4064)
			(end -0.7874 0.4064)
			(stroke
				(width 0.1524)
				(type default)
			)
			(layer "F.SilkS")
		)
		(fp_line
			(start -0.7874 0.4064)
			(end -0.7874 -0.4064)
			(stroke
				(width 0.1524)
				(type default)
			)
			(layer "F.SilkS")
		)
		(fp_line
			(start -0.12065 -0.305054)
			(end -0.12065 -0.2794)
			(stroke
				(width 0.1)
				(type default)
			)
			(layer "F.Fab")
		)
		(fp_line
			(start -0.67945 -0.305054)
			(end -0.12065 -0.305054)
			(stroke
				(width 0.1)
				(type default)
			)
			(layer "F.Fab")
		)
		(fp_line
			(start 0.67945 -0.3048)
			(end 0.67945 0.3048)
			(stroke
				(width 0.1)
				(type default)
			)
			(layer "F.Fab")
		)
		(fp_line
			(start 0.12065 -0.3048)
			(end 0.67945 -0.3048)
			(stroke
				(width 0.1)
				(type default)
			)
			(layer "F.Fab")
		)
		(fp_line
			(start 0.12065 -0.2794)
			(end 0.12065 -0.3048)
			(stroke
				(width 0.1)
				(type default)
			)
			(layer "F.Fab")
		)
		(fp_line
			(start -0.12065 -0.2794)
			(end 0.12065 -0.2794)
			(stroke
				(width 0.1)
				(type default)
			)
			(layer "F.Fab")
		)
		(fp_line
			(start 0.120396 0.2794)
			(end -0.12065 0.2794)
			(stroke
				(width 0.1)
				(type default)
			)
			(layer "F.Fab")
		)
		(fp_line
			(start -0.12065 0.2794)
			(end -0.12065 0.3048)
			(stroke
				(width 0.1)
				(type default)
			)
			(layer "F.Fab")
		)
		(fp_line
			(start 0.67945 0.3048)
			(end 0.120396 0.3048)
			(stroke
				(width 0.1)
				(type default)
			)
			(layer "F.Fab")
		)
		(fp_line
			(start 0.120396 0.3048)
			(end 0.120396 0.2794)
			(stroke
				(width 0.1)
				(type default)
			)
			(layer "F.Fab")
		)
		(fp_line
			(start -0.12065 0.3048)
			(end -0.67945 0.3048)
			(stroke
				(width 0.1)
				(type default)
			)
			(layer "F.Fab")
		)
		(fp_line
			(start -0.67945 0.3048)
			(end -0.67945 -0.305054)
			(stroke
				(width 0.1)
				(type default)
			)
			(layer "F.Fab")
		)
		(pad "1" smd circle
			(at -0.40005 0 90)
			(size 0 0)
			(layers "F.Cu" "F.Mask" "F.Paste")
			(net "USB2_HOST_BMC_B_DP")
		)
		(pad "2" smd circle
			(at 0.40005 0 90)
			(size 0 0)
			(layers "F.Cu" "F.Mask" "F.Paste")
			(net "GND")
		)
	)
	(footprint ""
		(layer "F.Cu")
		(at 452.13905 -47.475394 180)
		(property "Reference" "PC1870"
			(at 0 0 180)
			(layer "F.SilkS")
			(hide yes)
			(effects
				(font
					(size 1.27 1.27)
				)
			)
		)
		(property "Value" ""
			(at 0 0 180)
			(layer "F.Fab")
			(effects
				(font
					(size 1.27 1.27)
				)
			)
		)
		(duplicate_pad_numbers_are_jumpers no)
		(fp_line
			(start 0.7874 0.4064)
			(end -0.7874 0.4064)
			(stroke
				(width 0.1524)
				(type default)
			)
			(layer "F.SilkS")
		)
		(fp_line
			(start 0.7874 -0.4064)
			(end 0.7874 0.4064)
			(stroke
				(width 0.1524)
				(type default)
			)
			(layer "F.SilkS")
		)
		(fp_line
			(start -0.7874 0.4064)
			(end -0.7874 -0.4064)
			(stroke
				(width 0.1524)
				(type default)
			)
			(layer "F.SilkS")
		)
		(fp_line
			(start -0.7874 -0.4064)
			(end 0.7874 -0.4064)
			(stroke
				(width 0.1524)
				(type default)
			)
			(layer "F.SilkS")
		)
		(fp_line
			(start 0.67945 0.3048)
			(end 0.120396 0.3048)
			(stroke
				(width 0.1)
				(type default)
			)
			(layer "F.Fab")
		)
		(fp_line
			(start 0.67945 -0.3048)
			(end 0.67945 0.3048)
			(stroke
				(width 0.1)
				(type default)
			)
			(layer "F.Fab")
		)
		(fp_line
			(start 0.12065 -0.2794)
			(end 0.12065 -0.3048)
			(stroke
				(width 0.1)
				(type default)
			)
			(layer "F.Fab")
		)
		(fp_line
			(start 0.12065 -0.3048)
			(end 0.67945 -0.3048)
			(stroke
				(width 0.1)
				(type default)
			)
			(layer "F.Fab")
		)
		(fp_line
			(start 0.120396 0.3048)
			(end 0.120396 0.2794)
			(stroke
				(width 0.1)
				(type default)
			)
			(layer "F.Fab")
		)
		(fp_line
			(start 0.120396 0.2794)
			(end -0.12065 0.2794)
			(stroke
				(width 0.1)
				(type default)
			)
			(layer "F.Fab")
		)
		(fp_line
			(start -0.12065 0.3048)
			(end -0.67945 0.3048)
			(stroke
				(width 0.1)
				(type default)
			)
			(layer "F.Fab")
		)
		(fp_line
			(start -0.12065 0.2794)
			(end -0.12065 0.3048)
			(stroke
				(width 0.1)
				(type default)
			)
			(layer "F.Fab")
		)
		(fp_line
			(start -0.12065 -0.2794)
			(end 0.12065 -0.2794)
			(stroke
				(width 0.1)
				(type default)
			)
			(layer "F.Fab")
		)
		(fp_line
			(start -0.12065 -0.305054)
			(end -0.12065 -0.2794)
			(stroke
				(width 0.1)
				(type default)
			)
			(layer "F.Fab")
		)
		(fp_line
			(start -0.67945 0.3048)
			(end -0.67945 -0.305054)
			(stroke
				(width 0.1)
				(type default)
			)
			(layer "F.Fab")
		)
		(fp_line
			(start -0.67945 -0.305054)
			(end -0.12065 -0.305054)
			(stroke
				(width 0.1)
				(type default)
			)
			(layer "F.Fab")
		)
		(pad "1" smd circle
			(at -0.40005 0 180)
			(size 0 0)
			(layers "F.Cu" "F.Mask" "F.Paste")
			(net "P3V3_AUX_EN")
		)
		(pad "2" smd circle
			(at 0.40005 0 180)
			(size 0 0)
			(layers "F.Cu" "F.Mask" "F.Paste")
			(net "GND")
		)
	)
	(footprint ""
		(layer "F.Cu")
		(at 425.36872 -384.449828)
		(property "Reference" "C841"
			(at 0 0 0)
			(layer "F.SilkS")
			(hide yes)
			(effects
				(font
					(size 1.27 1.27)
				)
			)
		)
		(property "Value" ""
			(at 0 0 0)
			(layer "F.Fab")
			(effects
				(font
					(size 1.27 1.27)
				)
			)
		)
		(duplicate_pad_numbers_are_jumpers no)
		(fp_line
			(start -0.299974 -0.150114)
			(end 0.299974 -0.150114)
			(stroke
				(width 0.1)
				(type default)
			)
			(layer "F.Fab")
		)
		(fp_line
			(start -0.299974 0.150114)
			(end -0.299974 -0.150114)
			(stroke
				(width 0.1)
				(type default)
			)
			(layer "F.Fab")
		)
		(fp_line
			(start 0.299974 -0.150114)
			(end 0.299974 0.150114)
			(stroke
				(width 0.1)
				(type default)
			)
			(layer "F.Fab")
		)
		(fp_line
			(start 0.299974 0.150114)
			(end -0.299974 0.150114)
			(stroke
				(width 0.1)
				(type default)
			)
			(layer "F.Fab")
		)
		(pad "1" smd rect
			(at -0.2667 0)
			(size 0.3048 0.381)
			(layers "F.Cu" "F.Mask" "F.Paste")
			(net "P5E_CPU0_P2_TX_C_DP<14>")
		)
		(pad "2" smd rect
			(at 0.2667 0)
			(size 0.3048 0.381)
			(layers "F.Cu" "F.Mask" "F.Paste")
			(net "P5E_CPU0_P2_TX_DP<14>")
		)
	)
	(footprint ""
		(layer "F.Cu")
		(at 254.592836 -113.32845)
		(property "Reference" "R3729"
			(at 0 0 0)
			(layer "F.SilkS")
			(hide yes)
			(effects
				(font
					(size 1.27 1.27)
				)
			)
		)
		(property "Value" ""
			(at 0 0 0)
			(layer "F.Fab")
			(effects
				(font
					(size 1.27 1.27)
				)
			)
		)
		(duplicate_pad_numbers_are_jumpers no)
		(fp_line
			(start -0.7874 -0.4064)
			(end 0.7874 -0.4064)
			(stroke
				(width 0.1524)
				(type default)
			)
			(layer "F.SilkS")
		)
		(fp_line
			(start -0.7874 0.4064)
			(end -0.7874 -0.4064)
			(stroke
				(width 0.1524)
				(type default)
			)
			(layer "F.SilkS")
		)
		(fp_line
			(start 0.7874 -0.4064)
			(end 0.7874 0.4064)
			(stroke
				(width 0.1524)
				(type default)
			)
			(layer "F.SilkS")
		)
		(fp_line
			(start 0.7874 0.4064)
			(end -0.7874 0.4064)
			(stroke
				(width 0.1524)
				(type default)
			)
			(layer "F.SilkS")
		)
		(fp_line
			(start -0.67945 -0.305054)
			(end -0.12065 -0.305054)
			(stroke
				(width 0.1)
				(type default)
			)
			(layer "F.Fab")
		)
		(fp_line
			(start -0.67945 0.3048)
			(end -0.67945 -0.305054)
			(stroke
				(width 0.1)
				(type default)
			)
			(layer "F.Fab")
		)
		(fp_line
			(start -0.12065 -0.305054)
			(end -0.12065 -0.2794)
			(stroke
				(width 0.1)
				(type default)
			)
			(layer "F.Fab")
		)
		(fp_line
			(start -0.12065 -0.2794)
			(end 0.12065 -0.2794)
			(stroke
				(width 0.1)
				(type default)
			)
			(layer "F.Fab")
		)
		(fp_line
			(start -0.12065 0.2794)
			(end -0.12065 0.3048)
			(stroke
				(width 0.1)
				(type default)
			)
			(layer "F.Fab")
		)
		(fp_line
			(start -0.12065 0.3048)
			(end -0.67945 0.3048)
			(stroke
				(width 0.1)
				(type default)
			)
			(layer "F.Fab")
		)
		(fp_line
			(start 0.120396 0.2794)
			(end -0.12065 0.2794)
			(stroke
				(width 0.1)
				(type default)
			)
			(layer "F.Fab")
		)
		(fp_line
			(start 0.120396 0.3048)
			(end 0.120396 0.2794)
			(stroke
				(width 0.1)
				(type default)
			)
			(layer "F.Fab")
		)
		(fp_line
			(start 0.12065 -0.3048)
			(end 0.67945 -0.3048)
			(stroke
				(width 0.1)
				(type default)
			)
			(layer "F.Fab")
		)
		(fp_line
			(start 0.12065 -0.2794)
			(end 0.12065 -0.3048)
			(stroke
				(width 0.1)
				(type default)
			)
			(layer "F.Fab")
		)
		(fp_line
			(start 0.67945 -0.3048)
			(end 0.67945 0.3048)
			(stroke
				(width 0.1)
				(type default)
			)
			(layer "F.Fab")
		)
		(fp_line
			(start 0.67945 0.3048)
			(end 0.120396 0.3048)
			(stroke
				(width 0.1)
				(type default)
			)
			(layer "F.Fab")
		)
		(pad "1" smd circle
			(at -0.40005 0)
			(size 0 0)
			(layers "F.Cu" "F.Mask" "F.Paste")
			(net "P3V3_AUX")
		)
		(pad "2" smd circle
			(at 0.40005 0)
			(size 0 0)
			(layers "F.Cu" "F.Mask" "F.Paste")
			(net "SMB_LM75_2_3V3AUX_SCL")
		)
	)
	(footprint ""
		(layer "F.Cu")
		(at 18.302478 -17.623536 90)
		(property "Reference" "C680"
			(at 0 0 90)
			(layer "F.SilkS")
			(hide yes)
			(effects
				(font
					(size 1.27 1.27)
				)
			)
		)
		(property "Value" ""
			(at 0 0 90)
			(layer "F.Fab")
			(effects
				(font
					(size 1.27 1.27)
				)
			)
		)
		(duplicate_pad_numbers_are_jumpers no)
		(fp_line
			(start 0.299974 -0.150114)
			(end 0.299974 0.150114)
			(stroke
				(width 0.1)
				(type default)
			)
			(layer "F.Fab")
		)
		(fp_line
			(start -0.299974 -0.150114)
			(end 0.299974 -0.150114)
			(stroke
				(width 0.1)
				(type default)
			)
			(layer "F.Fab")
		)
		(fp_line
			(start 0.299974 0.150114)
			(end -0.299974 0.150114)
			(stroke
				(width 0.1)
				(type default)
			)
			(layer "F.Fab")
		)
		(fp_line
			(start -0.299974 0.150114)
			(end -0.299974 -0.150114)
			(stroke
				(width 0.1)
				(type default)
			)
			(layer "F.Fab")
		)
		(pad "1" smd rect
			(at -0.2667 0 90)
			(size 0.3048 0.381)
			(layers "F.Cu" "F.Mask" "F.Paste")
			(net "P5E_CPU1_G1_TX_C_DN<14>")
		)
		(pad "2" smd rect
			(at 0.2667 0 90)
			(size 0.3048 0.381)
			(layers "F.Cu" "F.Mask" "F.Paste")
			(net "P5E_CPU1_G1_TX_DN<14>")
		)
	)
	(footprint ""
		(layer "F.Cu")
		(at 76.53401 -24.713946 -90)
		(property "Reference" "PC2139"
			(at 0 0 270)
			(layer "F.SilkS")
			(hide yes)
			(effects
				(font
					(size 1.27 1.27)
				)
			)
		)
		(property "Value" ""
			(at 0 0 270)
			(layer "F.Fab")
			(effects
				(font
					(size 1.27 1.27)
				)
			)
		)
		(duplicate_pad_numbers_are_jumpers no)
		(fp_line
			(start -0.7874 0.4064)
			(end -0.7874 -0.4064)
			(stroke
				(width 0.1524)
				(type default)
			)
			(layer "F.SilkS")
		)
		(fp_line
			(start 0.7874 0.4064)
			(end -0.7874 0.4064)
			(stroke
				(width 0.1524)
				(type default)
			)
			(layer "F.SilkS")
		)
		(fp_line
			(start -0.7874 -0.4064)
			(end 0.7874 -0.4064)
			(stroke
				(width 0.1524)
				(type default)
			)
			(layer "F.SilkS")
		)
		(fp_line
			(start 0.7874 -0.4064)
			(end 0.7874 0.4064)
			(stroke
				(width 0.1524)
				(type default)
			)
			(layer "F.SilkS")
		)
		(fp_line
			(start -0.67945 0.3048)
			(end -0.67945 -0.305054)
			(stroke
				(width 0.1)
				(type default)
			)
			(layer "F.Fab")
		)
		(fp_line
			(start -0.12065 0.3048)
			(end -0.67945 0.3048)
			(stroke
				(width 0.1)
				(type default)
			)
			(layer "F.Fab")
		)
		(fp_line
			(start 0.120396 0.3048)
			(end 0.120396 0.2794)
			(stroke
				(width 0.1)
				(type default)
			)
			(layer "F.Fab")
		)
		(fp_line
			(start 0.67945 0.3048)
			(end 0.120396 0.3048)
			(stroke
				(width 0.1)
				(type default)
			)
			(layer "F.Fab")
		)
		(fp_line
			(start -0.12065 0.2794)
			(end -0.12065 0.3048)
			(stroke
				(width 0.1)
				(type default)
			)
			(layer "F.Fab")
		)
		(fp_line
			(start 0.120396 0.2794)
			(end -0.12065 0.2794)
			(stroke
				(width 0.1)
				(type default)
			)
			(layer "F.Fab")
		)
		(fp_line
			(start -0.12065 -0.2794)
			(end 0.12065 -0.2794)
			(stroke
				(width 0.1)
				(type default)
			)
			(layer "F.Fab")
		)
		(fp_line
			(start 0.12065 -0.2794)
			(end 0.12065 -0.3048)
			(stroke
				(width 0.1)
				(type default)
			)
			(layer "F.Fab")
		)
		(fp_line
			(start 0.12065 -0.3048)
			(end 0.67945 -0.3048)
			(stroke
				(width 0.1)
				(type default)
			)
			(layer "F.Fab")
		)
		(fp_line
			(start 0.67945 -0.3048)
			(end 0.67945 0.3048)
			(stroke
				(width 0.1)
				(type default)
			)
			(layer "F.Fab")
		)
		(fp_line
			(start -0.67945 -0.305054)
			(end -0.12065 -0.305054)
			(stroke
				(width 0.1)
				(type default)
			)
			(layer "F.Fab")
		)
		(fp_line
			(start -0.12065 -0.305054)
			(end -0.12065 -0.2794)
			(stroke
				(width 0.1)
				(type default)
			)
			(layer "F.Fab")
		)
		(pad "1" smd circle
			(at -0.40005 0 270)
			(size 0 0)
			(layers "F.Cu" "F.Mask" "F.Paste")
			(net "P12V_AUX")
		)
		(pad "2" smd circle
			(at 0.40005 0 270)
			(size 0 0)
			(layers "F.Cu" "F.Mask" "F.Paste")
			(net "GND")
		)
	)
)
